(kicad_pcb
	(version 20260206)
	(generator "pcbnew")
	(generator_version "10.0")
	(general
		(thickness 1.6)
		(legacy_teardrops no)
	)
	(paper "A4")
	(title_block
		(title "Bryce Canyon_IOM_IOC_16318-2_OCP.brd")
		(comment 1 "Bryce Canyon / footprints 708-714 of 1605")
	)
	(layers
		(0 "F.Cu" signal "TOP")
		(4 "In1.Cu" signal "L2GND")
		(6 "In2.Cu" signal "L3")
		(8 "In3.Cu" signal "L4VCC")
		(10 "In4.Cu" signal "L5VCC")
		(12 "In5.Cu" signal "L6")
		(14 "In6.Cu" signal "L7GND")
		(2 "B.Cu" signal "BOTTOM")
		(9 "F.Adhes" user "F.Adhesive")
		(11 "B.Adhes" user "B.Adhesive")
		(13 "F.Paste" user "Package Geometry/Pastemask Top")
		(15 "B.Paste" user "Package Geometry/Pastemask Bottom")
		(5 "F.SilkS" user "Ref Des/Silkscreen Top")
		(7 "B.SilkS" user "Ref Des/Silkscreen Bottom")
		(1 "F.Mask" user "Board Geometry/Soldermask Top")
		(3 "B.Mask" user "Board Geometry/Soldermask Bottom")
		(17 "Dwgs.User" user "User.Drawings")
		(19 "Cmts.User" user "User.Comments")
		(21 "Eco1.User" user "User.Eco1")
		(23 "Eco2.User" user "User.Eco2")
		(25 "Edge.Cuts" user "Board Geometry/Outline")
		(27 "Margin" user)
		(31 "F.CrtYd" user "Package Geometry/Place Bound Top")
		(29 "B.CrtYd" user "Package Geometry/Place Bound Bottom")
		(35 "F.Fab" user "Ref Des/Assembly Top")
		(33 "B.Fab" user "Ref Des/Assembly Bottom")
	)
	(footprint ""
		(layer "F.Cu")
		(at 71.189342 -161.96437 90)
		(property "Reference" "C240"
			(at 0 0 90)
			(layer "F.SilkS")
			(hide yes)
			(effects
				(font
					(size 1.27 1.27)
				)
			)
		)
		(property "Value" "SC470P50V2KX-3GP"
			(at 1.1811 -2.7051 90)
			(unlocked yes)
			(layer "F.Fab")
			(hide yes)
			(effects
				(font
					(size 1.016 1.016)
					(thickness 0.1524)
				)
			)
		)
		(property "Device Type" "C402H22"
			(at 1.1811 -4.2291 90)
			(unlocked yes)
			(layer "F.Fab")
			(hide yes)
			(effects
				(font
					(size 1.016 1.016)
					(thickness 0.1524)
				)
			)
		)
		(duplicate_pad_numbers_are_jumpers no)
		(fp_rect
			(start -0.4318 0.9525)
			(end 0.4318 -0.9525)
			(stroke
				(width 0)
				(type default)
			)
			(fill no)
			(layer "F.CrtYd")
		)
		(fp_rect
			(start -0.4318 0.9525)
			(end 0.4318 -0.9525)
			(stroke
				(width 0)
				(type default)
			)
			(fill no)
			(layer "F.Fab")
		)
		(pad "1" smd custom
			(at 0 -0.4445 90)
			(size 0.1524 0.1524)
			(layers "F.Cu" "F.Mask" "F.Paste")
			(net "GND")
			(options
				(clearance outline)
				(anchor circle)
			)
			(primitives
				(gr_poly
					(pts
						(arc
							(start 0.3048 -0.2032)
							(mid 0.275042 -0.275042)
							(end 0.2032 -0.3048)
						)
						(arc
							(start -0.2032 -0.3048)
							(mid -0.275042 -0.275042)
							(end -0.3048 -0.2032)
						)
						(arc
							(start -0.3048 0.2032)
							(mid -0.275042 0.275042)
							(end -0.2032 0.3048)
						)
						(arc
							(start 0.2032 0.3048)
							(mid 0.275042 0.275042)
							(end 0.3048 0.2032)
						)
					)
					(width 0)
					(fill yes)
				)
			)
		)
		(pad "2" smd custom
			(at 0 0.4445 90)
			(size 0.1524 0.1524)
			(layers "F.Cu" "F.Mask" "F.Paste")
			(net "TPS74801_P1V15_STBY_SS")
			(options
				(clearance outline)
				(anchor circle)
			)
			(primitives
				(gr_poly
					(pts
						(arc
							(start 0.3048 -0.2032)
							(mid 0.275042 -0.275042)
							(end 0.2032 -0.3048)
						)
						(arc
							(start -0.2032 -0.3048)
							(mid -0.275042 -0.275042)
							(end -0.3048 -0.2032)
						)
						(arc
							(start -0.3048 0.2032)
							(mid -0.275042 0.275042)
							(end -0.2032 0.3048)
						)
						(arc
							(start 0.2032 0.3048)
							(mid 0.275042 0.275042)
							(end 0.3048 0.2032)
						)
					)
					(width 0)
					(fill yes)
				)
			)
		)
	)
	(footprint ""
		(layer "F.Cu")
		(at 66.439542 -161.123122 90)
		(property "Reference" "R775"
			(at 0 0 90)
			(layer "F.SilkS")
			(hide yes)
			(effects
				(font
					(size 1.27 1.27)
				)
			)
		)
		(property "Value" "1KR2F-3-GP"
			(at 0.064008 -3.993896 90)
			(unlocked yes)
			(layer "F.Fab")
			(hide yes)
			(effects
				(font
					(size 1.016 1.016)
					(thickness 0.1524)
				)
			)
		)
		(property "Device Type" "R402H16"
			(at 0.064008 -5.517896 90)
			(unlocked yes)
			(layer "F.Fab")
			(hide yes)
			(effects
				(font
					(size 1.016 1.016)
					(thickness 0.1524)
				)
			)
		)
		(duplicate_pad_numbers_are_jumpers no)
		(fp_line
			(start 0.508 -0.9398)
			(end -0.508 -0.9398)
			(stroke
				(width 0.1524)
				(type default)
			)
			(layer "F.SilkS")
		)
		(fp_line
			(start -0.508 -0.9398)
			(end -0.508 0.9398)
			(stroke
				(width 0.1524)
				(type default)
			)
			(layer "F.SilkS")
		)
		(fp_rect
			(start -0.508 0.9398)
			(end 0.508 -0.9398)
			(stroke
				(width 0)
				(type default)
			)
			(fill no)
			(layer "F.CrtYd")
		)
		(fp_rect
			(start -0.508 0.9398)
			(end 0.508 -0.9398)
			(stroke
				(width 0)
				(type default)
			)
			(fill no)
			(layer "F.Fab")
		)
		(pad "1" smd custom
			(at 0 -0.4445 90)
			(size 0.1397 0.1397)
			(layers "F.Cu" "F.Mask" "F.Paste")
			(net "ADC_P1V15_STBY")
			(options
				(clearance outline)
				(anchor circle)
			)
			(primitives
				(gr_poly
					(pts
						(arc
							(start -0.1778 -0.2794)
							(mid -0.249642 -0.249642)
							(end -0.2794 -0.1778)
						)
						(arc
							(start -0.2794 0.1778)
							(mid -0.249642 0.249642)
							(end -0.1778 0.2794)
						)
						(arc
							(start 0.1778 0.2794)
							(mid 0.249642 0.249642)
							(end 0.2794 0.1778)
						)
						(arc
							(start 0.2794 -0.1778)
							(mid 0.249642 -0.249642)
							(end 0.1778 -0.2794)
						)
					)
					(width 0)
					(fill yes)
				)
			)
		)
		(pad "2" smd custom
			(at 0 0.4445 90)
			(size 0.1397 0.1397)
			(layers "F.Cu" "F.Mask" "F.Paste")
			(net "GND")
			(options
				(clearance outline)
				(anchor circle)
			)
			(primitives
				(gr_poly
					(pts
						(arc
							(start -0.1778 -0.2794)
							(mid -0.249642 -0.249642)
							(end -0.2794 -0.1778)
						)
						(arc
							(start -0.2794 0.1778)
							(mid -0.249642 0.249642)
							(end -0.1778 0.2794)
						)
						(arc
							(start 0.1778 0.2794)
							(mid 0.249642 0.249642)
							(end 0.2794 0.1778)
						)
						(arc
							(start 0.2794 -0.1778)
							(mid 0.249642 -0.249642)
							(end 0.1778 -0.2794)
						)
					)
					(width 0)
					(fill yes)
				)
			)
		)
	)
	(footprint ""
		(layer "F.Cu")
		(at 46.778418 -128.189736)
		(property "Reference" "R200"
			(at 0 0 0)
			(layer "F.SilkS")
			(hide yes)
			(effects
				(font
					(size 1.27 1.27)
				)
			)
		)
		(property "Value" "2K2R2F-GP"
			(at 0.064008 -3.993896 0)
			(unlocked yes)
			(layer "F.Fab")
			(hide yes)
			(effects
				(font
					(size 1.016 1.016)
					(thickness 0.1524)
				)
			)
		)
		(property "Device Type" "R402H16"
			(at 0.064008 -5.517896 0)
			(unlocked yes)
			(layer "F.Fab")
			(hide yes)
			(effects
				(font
					(size 1.016 1.016)
					(thickness 0.1524)
				)
			)
		)
		(duplicate_pad_numbers_are_jumpers no)
		(fp_line
			(start -0.508 -0.9398)
			(end -0.508 0.9398)
			(stroke
				(width 0.1524)
				(type default)
			)
			(layer "F.SilkS")
		)
		(fp_line
			(start 0.508 -0.9398)
			(end -0.508 -0.9398)
			(stroke
				(width 0.1524)
				(type default)
			)
			(layer "F.SilkS")
		)
		(fp_rect
			(start -0.508 0.9398)
			(end 0.508 -0.9398)
			(stroke
				(width 0)
				(type default)
			)
			(fill no)
			(layer "F.CrtYd")
		)
		(fp_rect
			(start -0.508 0.9398)
			(end 0.508 -0.9398)
			(stroke
				(width 0)
				(type default)
			)
			(fill no)
			(layer "F.Fab")
		)
		(pad "1" smd custom
			(at 0 -0.4445)
			(size 0.1397 0.1397)
			(layers "F.Cu" "F.Mask" "F.Paste")
			(net "I2C_TPM_SCL")
			(options
				(clearance outline)
				(anchor circle)
			)
			(primitives
				(gr_poly
					(pts
						(arc
							(start -0.1778 -0.2794)
							(mid -0.249642 -0.249642)
							(end -0.2794 -0.1778)
						)
						(arc
							(start -0.2794 0.1778)
							(mid -0.249642 0.249642)
							(end -0.1778 0.2794)
						)
						(arc
							(start 0.1778 0.2794)
							(mid 0.249642 0.249642)
							(end 0.2794 0.1778)
						)
						(arc
							(start 0.2794 -0.1778)
							(mid 0.249642 -0.249642)
							(end 0.1778 -0.2794)
						)
					)
					(width 0)
					(fill yes)
				)
			)
		)
		(pad "2" smd custom
			(at 0 0.4445)
			(size 0.1397 0.1397)
			(layers "F.Cu" "F.Mask" "F.Paste")
			(net "P3V3_STBY")
			(options
				(clearance outline)
				(anchor circle)
			)
			(primitives
				(gr_poly
					(pts
						(arc
							(start -0.1778 -0.2794)
							(mid -0.249642 -0.249642)
							(end -0.2794 -0.1778)
						)
						(arc
							(start -0.2794 0.1778)
							(mid -0.249642 0.249642)
							(end -0.1778 0.2794)
						)
						(arc
							(start 0.1778 0.2794)
							(mid 0.249642 0.249642)
							(end 0.2794 0.1778)
						)
						(arc
							(start 0.2794 -0.1778)
							(mid 0.249642 -0.249642)
							(end 0.1778 -0.2794)
						)
					)
					(width 0)
					(fill yes)
				)
			)
		)
	)
	(footprint ""
		(layer "F.Cu")
		(at 208.055972 -71.12 90)
		(property "Reference" "C314"
			(at 0 0 90)
			(layer "F.SilkS")
			(hide yes)
			(effects
				(font
					(size 1.27 1.27)
				)
			)
		)
		(property "Value" "SCD01U16V1KX-GP"
			(at -2.8321 -1.7399 90)
			(unlocked yes)
			(layer "F.Fab")
			(hide yes)
			(effects
				(font
					(size 1.016 1.016)
					(thickness 0.1524)
				)
			)
		)
		(property "Device Type" "C0201H13"
			(at -2.8321 -3.2639 90)
			(unlocked yes)
			(layer "F.Fab")
			(hide yes)
			(effects
				(font
					(size 1.016 1.016)
					(thickness 0.1524)
				)
			)
		)
		(duplicate_pad_numbers_are_jumpers no)
		(fp_rect
			(start -0.2794 0.6477)
			(end 0.2794 -0.6477)
			(stroke
				(width 0)
				(type default)
			)
			(fill no)
			(layer "F.CrtYd")
		)
		(fp_rect
			(start -0.2794 0.6477)
			(end 0.2794 -0.6477)
			(stroke
				(width 0)
				(type default)
			)
			(fill no)
			(layer "F.Fab")
		)
		(pad "1" smd custom
			(at 0 -0.2794 90)
			(size 0.0762 0.0762)
			(layers "F.Cu" "F.Mask" "F.Paste")
			(net "PHY_IOC_TO_CON_A_3_DN_C")
			(options
				(clearance outline)
				(anchor circle)
			)
			(primitives
				(gr_poly
					(pts
						(arc
							(start 0.1524 -0.127)
							(mid 0.137521 -0.162921)
							(end 0.1016 -0.1778)
						)
						(arc
							(start -0.1016 -0.1778)
							(mid -0.137521 -0.162921)
							(end -0.1524 -0.127)
						)
						(arc
							(start -0.1524 0.127)
							(mid -0.137521 0.162921)
							(end -0.1016 0.1778)
						)
						(arc
							(start 0.1016 0.1778)
							(mid 0.137521 0.162921)
							(end 0.1524 0.127)
						)
					)
					(width 0)
					(fill yes)
				)
			)
		)
		(pad "2" smd custom
			(at 0 0.2794 90)
			(size 0.0762 0.0762)
			(layers "F.Cu" "F.Mask" "F.Paste")
			(net "PHY_IOC_TO_CON_A_3_DN")
			(options
				(clearance outline)
				(anchor circle)
			)
			(primitives
				(gr_poly
					(pts
						(arc
							(start 0.1524 -0.127)
							(mid 0.137521 -0.162921)
							(end 0.1016 -0.1778)
						)
						(arc
							(start -0.1016 -0.1778)
							(mid -0.137521 -0.162921)
							(end -0.1524 -0.127)
						)
						(arc
							(start -0.1524 0.127)
							(mid -0.137521 0.162921)
							(end -0.1016 0.1778)
						)
						(arc
							(start 0.1016 0.1778)
							(mid 0.137521 0.162921)
							(end 0.1524 0.127)
						)
					)
					(width 0)
					(fill yes)
				)
			)
		)
	)
	(footprint ""
		(layer "F.Cu")
		(at 208.055972 -76.1492 90)
		(property "Reference" "C308"
			(at 0 0 90)
			(layer "F.SilkS")
			(hide yes)
			(effects
				(font
					(size 1.27 1.27)
				)
			)
		)
		(property "Value" "SCD01U16V1KX-GP"
			(at -2.8321 -1.7399 90)
			(unlocked yes)
			(layer "F.Fab")
			(hide yes)
			(effects
				(font
					(size 1.016 1.016)
					(thickness 0.1524)
				)
			)
		)
		(property "Device Type" "C0201H13"
			(at -2.8321 -3.2639 90)
			(unlocked yes)
			(layer "F.Fab")
			(hide yes)
			(effects
				(font
					(size 1.016 1.016)
					(thickness 0.1524)
				)
			)
		)
		(duplicate_pad_numbers_are_jumpers no)
		(fp_rect
			(start -0.2794 0.6477)
			(end 0.2794 -0.6477)
			(stroke
				(width 0)
				(type default)
			)
			(fill no)
			(layer "F.CrtYd")
		)
		(fp_rect
			(start -0.2794 0.6477)
			(end 0.2794 -0.6477)
			(stroke
				(width 0)
				(type default)
			)
			(fill no)
			(layer "F.Fab")
		)
		(pad "1" smd custom
			(at 0 -0.2794 90)
			(size 0.0762 0.0762)
			(layers "F.Cu" "F.Mask" "F.Paste")
			(net "PHY_IOC_TO_CON_A_0_DN_C")
			(options
				(clearance outline)
				(anchor circle)
			)
			(primitives
				(gr_poly
					(pts
						(arc
							(start 0.1524 -0.127)
							(mid 0.137521 -0.162921)
							(end 0.1016 -0.1778)
						)
						(arc
							(start -0.1016 -0.1778)
							(mid -0.137521 -0.162921)
							(end -0.1524 -0.127)
						)
						(arc
							(start -0.1524 0.127)
							(mid -0.137521 0.162921)
							(end -0.1016 0.1778)
						)
						(arc
							(start 0.1016 0.1778)
							(mid 0.137521 0.162921)
							(end 0.1524 0.127)
						)
					)
					(width 0)
					(fill yes)
				)
			)
		)
		(pad "2" smd custom
			(at 0 0.2794 90)
			(size 0.0762 0.0762)
			(layers "F.Cu" "F.Mask" "F.Paste")
			(net "PHY_IOC_TO_CON_A_0_DN")
			(options
				(clearance outline)
				(anchor circle)
			)
			(primitives
				(gr_poly
					(pts
						(arc
							(start 0.1524 -0.127)
							(mid 0.137521 -0.162921)
							(end 0.1016 -0.1778)
						)
						(arc
							(start -0.1016 -0.1778)
							(mid -0.137521 -0.162921)
							(end -0.1524 -0.127)
						)
						(arc
							(start -0.1524 0.127)
							(mid -0.137521 0.162921)
							(end -0.1016 0.1778)
						)
						(arc
							(start 0.1016 0.1778)
							(mid 0.137521 0.162921)
							(end 0.1524 0.127)
						)
					)
					(width 0)
					(fill yes)
				)
			)
		)
	)
	(footprint ""
		(layer "F.Cu")
		(at 223.576642 -98.454718)
		(property "Reference" "R687"
			(at 0 0 0)
			(layer "F.SilkS")
			(hide yes)
			(effects
				(font
					(size 1.27 1.27)
				)
			)
		)
		(property "Value" "D51R3F-2-GP"
			(at -0.0254 -2.5146 0)
			(unlocked yes)
			(layer "F.Fab")
			(hide yes)
			(effects
				(font
					(size 1.016 1.016)
					(thickness 0.1524)
				)
			)
		)
		(property "Device Type" "R603H22"
			(at -0.0254 -4.0386 0)
			(unlocked yes)
			(layer "F.Fab")
			(hide yes)
			(effects
				(font
					(size 1.016 1.016)
					(thickness 0.1524)
				)
			)
		)
		(duplicate_pad_numbers_are_jumpers no)
		(fp_line
			(start -0.4826 0)
			(end -0.2032 0)
			(stroke
				(width 0.2032)
				(type default)
			)
			(layer "F.SilkS")
		)
		(fp_line
			(start 0.2032 0)
			(end 0.4826 0)
			(stroke
				(width 0.2032)
				(type default)
			)
			(layer "F.SilkS")
		)
		(fp_rect
			(start -0.5842 1.3335)
			(end 0.5842 -1.3335)
			(stroke
				(width 0)
				(type default)
			)
			(fill no)
			(layer "F.CrtYd")
		)
		(fp_rect
			(start -0.5842 1.3335)
			(end 0.5842 -1.3335)
			(stroke
				(width 0)
				(type default)
			)
			(fill no)
			(layer "F.Fab")
		)
		(pad "1" smd custom
			(at 0 -0.762)
			(size 0.2159 0.2159)
			(layers "F.Cu" "F.Mask" "F.Paste")
			(net "P0V975")
			(options
				(clearance outline)
				(anchor circle)
			)
			(primitives
				(gr_poly
					(pts
						(arc
							(start -0.3302 -0.4318)
							(mid -0.402042 -0.402042)
							(end -0.4318 -0.3302)
						)
						(arc
							(start -0.4318 0.3302)
							(mid -0.402042 0.402042)
							(end -0.3302 0.4318)
						)
						(arc
							(start 0.3302 0.4318)
							(mid 0.402042 0.402042)
							(end 0.4318 0.3302)
						)
						(arc
							(start 0.4318 -0.3302)
							(mid 0.402042 -0.402042)
							(end 0.3302 -0.4318)
						)
					)
					(width 0)
					(fill yes)
				)
			)
		)
		(pad "2" smd custom
			(at 0 0.762)
			(size 0.2159 0.2159)
			(layers "F.Cu" "F.Mask" "F.Paste")
			(net "SAS0_AVDD")
			(options
				(clearance outline)
				(anchor circle)
			)
			(primitives
				(gr_poly
					(pts
						(arc
							(start -0.3302 -0.4318)
							(mid -0.402042 -0.402042)
							(end -0.4318 -0.3302)
						)
						(arc
							(start -0.4318 0.3302)
							(mid -0.402042 0.402042)
							(end -0.3302 0.4318)
						)
						(arc
							(start 0.3302 0.4318)
							(mid 0.402042 0.402042)
							(end 0.4318 0.3302)
						)
						(arc
							(start 0.4318 -0.3302)
							(mid 0.402042 -0.402042)
							(end 0.3302 -0.4318)
						)
					)
					(width 0)
					(fill yes)
				)
			)
		)
	)
	(footprint ""
		(layer "F.Cu")
		(at 128.917446 -8.750808 90)
		(property "Reference" "R709"
			(at 0 0 90)
			(layer "F.SilkS")
			(hide yes)
			(effects
				(font
					(size 1.27 1.27)
				)
			)
		)
		(property "Value" "0R5J-5-GP"
			(at 0 -8.9535 90)
			(unlocked yes)
			(layer "F.Fab")
			(hide yes)
			(effects
				(font
					(size 1.27 1.016)
					(thickness 0.1524)
				)
			)
		)
		(property "Device Type" "R805H24"
			(at 0 -10.6299 90)
			(unlocked yes)
			(layer "F.Fab")
			(hide yes)
			(effects
				(font
					(size 1.27 1.016)
					(thickness 0.1524)
				)
			)
		)
		(duplicate_pad_numbers_are_jumpers no)
		(fp_line
			(start 0.889 -1.7018)
			(end -0.889 -1.7018)
			(stroke
				(width 0.1524)
				(type default)
			)
			(layer "F.SilkS")
		)
		(fp_line
			(start 0.889 -1.7018)
			(end 0.889 -0.381)
			(stroke
				(width 0.1524)
				(type default)
			)
			(layer "F.SilkS")
		)
		(fp_line
			(start -0.889 -1.7018)
			(end -0.889 0.2794)
			(stroke
				(width 0.1524)
				(type default)
			)
			(layer "F.SilkS")
		)
		(fp_line
			(start -0.889 0.0762)
			(end -0.889 1.7018)
			(stroke
				(width 0.1524)
				(type default)
			)
			(layer "F.SilkS")
		)
		(fp_line
			(start 0.889 1.7018)
			(end 0.889 -0.508)
			(stroke
				(width 0.1524)
				(type default)
			)
			(layer "F.SilkS")
		)
		(fp_line
			(start -0.889 1.7018)
			(end 0.889 1.7018)
			(stroke
				(width 0.1524)
				(type default)
			)
			(layer "F.SilkS")
		)
		(fp_poly
			(pts
				(xy 0.9652 -1.778) (xy 0.9652 1.778) (xy -0.9652 1.778) (xy -0.9652 -1.778)
			)
			(stroke
				(width 0)
				(type default)
			)
			(fill no)
			(layer "F.CrtYd")
		)
		(fp_rect
			(start -0.9652 1.778)
			(end 0.9652 -1.778)
			(stroke
				(width 0)
				(type default)
			)
			(fill no)
			(layer "F.Fab")
		)
		(pad "1" smd rect
			(at 0 -0.9652 90)
			(size 1.397 1.143)
			(layers "F.Cu" "F.Mask" "F.Paste")
			(net "MB0_CM_GATE_2")
		)
		(pad "2" smd rect
			(at 0 0.9652 90)
			(size 1.397 1.143)
			(layers "F.Cu" "F.Mask" "F.Paste")
			(net "MB0_CM_GATE_R")
		)
	)
)
